# TIMECARD (Time Appliance Project (Time Card)) — schematic netlist excerpt (pin names and nets, part order shuffled) for the footprints in the layout excerpt that follows; sources: Cadence DE-HDL packaged netlist, KiCad conversion of R4006-B0001-02_R01.brd

R64  RESISTOR  4.7KOHM 1%  pkg SMC_0402R_H016  page 18 : \1\ = XP3R3V_FPGA ; \2\ = SHT3X_I2C_SDA
R318  RESISTOR  10KOHM 1%  pkg SMC_0402R_H016  page 26 : \1\ = XP3R3V_FPGA ; \2\ = R_RGB_LED_I2C_SCL

(kicad_pcb
	(version 20260206)
	(generator "pcbnew")
	(generator_version "10.0")
	(general
		(thickness 1.6)
		(legacy_teardrops no)
	)
	(paper "A4")
	(title_block
		(title "timecard-production-celestica-r4006 — R4006-B0001-02_R01.brd")
		(comment 1 "Time Appliance Project (Time Card) / footprints 938-939 of 1113")
	)
	(layers
		(0 "F.Cu" signal "TOP")
		(4 "In1.Cu" signal "L02_GND1")
		(6 "In2.Cu" signal "L03_SIG1")
		(8 "In3.Cu" signal "L04_GND2")
		(10 "In4.Cu" signal "L05_VCC1")
		(12 "In5.Cu" signal "L06_VCC2")
		(14 "In6.Cu" signal "L07_GND3")
		(16 "In7.Cu" signal "L08_SIG2")
		(18 "In8.Cu" signal "L09_GND4")
		(2 "B.Cu" signal "BOTTOM")
		(9 "F.Adhes" user "F.Adhesive")
		(11 "B.Adhes" user "B.Adhesive")
		(13 "F.Paste" user "Package Geometry/Pastemask Top")
		(15 "B.Paste" user "Package Geometry/Pastemask Bottom")
		(5 "F.SilkS" user "Ref Des/Silkscreen Top")
		(7 "B.SilkS" user "Ref Des/Silkscreen Bottom")
		(1 "F.Mask" user "Board Geometry/Soldermask Top")
		(3 "B.Mask" user "Board Geometry/Soldermask Bottom")
		(17 "Dwgs.User" user "User.Drawings")
		(19 "Cmts.User" user "User.Comments")
		(21 "Eco1.User" user "User.Eco1")
		(23 "Eco2.User" user "User.Eco2")
		(25 "Edge.Cuts" user "Board Geometry/Outline")
		(27 "Margin" user)
		(31 "F.CrtYd" user "Package Geometry/Place Bound Top")
		(29 "B.CrtYd" user "Package Geometry/Place Bound Bottom")
		(35 "F.Fab" user "Ref Des/Assembly Top")
		(33 "B.Fab" user "Ref Des/Assembly Bottom")
	)
	(footprint ""
		(layer "B.Cu")
		(at 107.823 -104.521 180)
		(property "Reference" "R318"
			(at -0.127 2.88163 0)
			(unlocked yes)
			(layer "B.SilkS")
			(effects
				(font
					(size 0.7874 0.5842)
					(thickness 0.1524)
				)
				(justify mirror)
			)
		)
		(property "Value" "VAL*"
			(at -0.02032 2.13233 180)
			(unlocked yes)
			(layer "B.Fab")
			(hide yes)
			(effects
				(font
					(size 0.7874 0.5842)
					(thickness 0.1524)
				)
				(justify mirror)
			)
		)
		(property "Tolerance" "TOL*"
			(at -0.044704 3.05435 180)
			(unlocked yes)
			(layer "Cmts.User")
			(hide yes)
			(effects
				(font
					(size 0.7874 0.5842)
					(thickness 0.1524)
				)
				(justify mirror)
			)
		)
		(property "User Part Number" "PARTNUM*"
			(at -0.02032 4.024884 180)
			(unlocked yes)
			(layer "Cmts.User")
			(hide yes)
			(effects
				(font
					(size 0.7874 0.5842)
					(thickness 0.1524)
				)
				(justify mirror)
			)
		)
		(property "Device Type" "RESISTOR-G155-11002-01,10KOHM,A"
			(at -0.008382 1.210564 180)
			(unlocked yes)
			(layer "B.Fab")
			(hide yes)
			(effects
				(font
					(size 0.7874 0.5842)
					(thickness 0.1524)
				)
				(justify mirror)
			)
		)
		(duplicate_pad_numbers_are_jumpers no)
		(fp_line
			(start 1.143 0.5588)
			(end -1.143 0.5588)
			(stroke
				(width 0.1)
				(type default)
			)
			(layer "B.SilkS")
		)
		(fp_line
			(start 1.143 -0.5588)
			(end 1.143 0.5588)
			(stroke
				(width 0.1)
				(type default)
			)
			(layer "B.SilkS")
		)
		(fp_line
			(start -1.143 0.5588)
			(end -1.143 -0.5588)
			(stroke
				(width 0.1)
				(type default)
			)
			(layer "B.SilkS")
		)
		(fp_line
			(start -1.143 -0.5588)
			(end 1.143 -0.5588)
			(stroke
				(width 0.1)
				(type default)
			)
			(layer "B.SilkS")
		)
		(fp_poly
			(pts
				(xy 1.143 0.5588) (xy -1.143 0.5588) (xy -1.143 -0.5588) (xy 1.143 -0.5588)
			)
			(stroke
				(width 0)
				(type default)
			)
			(fill no)
			(layer "B.CrtYd")
		)
		(fp_line
			(start 0.508 0.3048)
			(end -0.508 0.3048)
			(stroke
				(width 0.1)
				(type default)
			)
			(layer "B.Fab")
		)
		(fp_line
			(start 0.508 -0.3048)
			(end 0.508 0.3048)
			(stroke
				(width 0.1)
				(type default)
			)
			(layer "B.Fab")
		)
		(fp_line
			(start -0.508 0.3048)
			(end -0.508 -0.3048)
			(stroke
				(width 0.1)
				(type default)
			)
			(layer "B.Fab")
		)
		(fp_line
			(start -0.508 -0.3048)
			(end 0.508 -0.3048)
			(stroke
				(width 0.1)
				(type default)
			)
			(layer "B.Fab")
		)
		(pad "1" smd rect
			(at 0.5334 0)
			(size 0.7112 0.6096)
			(layers "B.Cu" "B.Mask" "B.Paste")
			(net "XP3R3V_FPGA")
		)
		(pad "2" smd rect
			(at -0.5334 0)
			(size 0.7112 0.6096)
			(layers "B.Cu" "B.Mask" "B.Paste")
			(net "R_RGB_LED_I2C_SCL")
		)
		(zone
			(layer "B.Cu")
			(hatch none 0.5)
			(connect_pads
				(clearance 0)
			)
			(min_thickness 0.25)
			(keepout
				(tracks not_allowed)
				(vias allowed)
				(pads allowed)
				(copperpour not_allowed)
				(footprints allowed)
			)
			(placement
				(enabled no)
				(sheetname "")
			)
			(fill
				(thermal_gap 0.5)
				(thermal_bridge_width 0.5)
				(island_removal_mode 0)
			)
			(polygon
				(pts
					(xy 107.7468 -104.8258) (xy 107.7468 -104.2162) (xy 107.8992 -104.2162) (xy 107.8992 -104.8258)
				)
			)
		)
		(zone
			(layer "B.Cu")
			(hatch none 0.5)
			(connect_pads
				(clearance 0)
			)
			(min_thickness 0.25)
			(keepout
				(tracks allowed)
				(vias not_allowed)
				(pads allowed)
				(copperpour not_allowed)
				(footprints allowed)
			)
			(placement
				(enabled no)
				(sheetname "")
			)
			(fill
				(thermal_gap 0.5)
				(thermal_bridge_width 0.5)
				(island_removal_mode 0)
			)
			(polygon
				(pts
					(xy 107.7468 -104.8258) (xy 107.7468 -104.2162) (xy 107.8992 -104.2162) (xy 107.8992 -104.8258)
				)
			)
		)
	)
	(footprint ""
		(layer "B.Cu")
		(at 150.343108 -49.01311 -90)
		(property "Reference" "R64"
			(at -3.81889 0.776478 270)
			(unlocked yes)
			(layer "B.SilkS")
			(effects
				(font
					(size 0.7874 0.5842)
					(thickness 0.1524)
				)
				(justify mirror)
			)
		)
		(property "Value" "VAL*"
			(at -0.02032 2.13233 270)
			(unlocked yes)
			(layer "B.Fab")
			(hide yes)
			(effects
				(font
					(size 0.7874 0.5842)
					(thickness 0.1524)
				)
				(justify mirror)
			)
		)
		(property "Device Type" "RESISTOR-G155-14701-01,4.7KOHMA"
			(at -0.008382 1.210564 270)
			(unlocked yes)
			(layer "B.Fab")
			(hide yes)
			(effects
				(font
					(size 0.7874 0.5842)
					(thickness 0.1524)
				)
				(justify mirror)
			)
		)
		(property "User Part Number" "PARTNUM*"
			(at -0.02032 4.024884 270)
			(unlocked yes)
			(layer "Cmts.User")
			(hide yes)
			(effects
				(font
					(size 0.7874 0.5842)
					(thickness 0.1524)
				)
				(justify mirror)
			)
		)
		(property "Tolerance" "TOL*"
			(at -0.044704 3.05435 270)
			(unlocked yes)
			(layer "Cmts.User")
			(hide yes)
			(effects
				(font
					(size 0.7874 0.5842)
					(thickness 0.1524)
				)
				(justify mirror)
			)
		)
		(duplicate_pad_numbers_are_jumpers no)
		(fp_line
			(start -1.143 0.5588)
			(end -1.143 -0.5588)
			(stroke
				(width 0.1)
				(type default)
			)
			(layer "B.SilkS")
		)
		(fp_line
			(start 1.143 0.5588)
			(end -1.143 0.5588)
			(stroke
				(width 0.1)
				(type default)
			)
			(layer "B.SilkS")
		)
		(fp_line
			(start -1.143 -0.5588)
			(end 1.143 -0.5588)
			(stroke
				(width 0.1)
				(type default)
			)
			(layer "B.SilkS")
		)
		(fp_line
			(start 1.143 -0.5588)
			(end 1.143 0.5588)
			(stroke
				(width 0.1)
				(type default)
			)
			(layer "B.SilkS")
		)
		(fp_rect
			(start 1.143 0.5588)
			(end -1.143 -0.5588)
			(stroke
				(width 0)
				(type default)
			)
			(fill no)
			(layer "B.CrtYd")
		)
		(fp_line
			(start -0.508 0.3048)
			(end -0.508 -0.3048)
			(stroke
				(width 0.1)
				(type default)
			)
			(layer "B.Fab")
		)
		(fp_line
			(start 0.508 0.3048)
			(end -0.508 0.3048)
			(stroke
				(width 0.1)
				(type default)
			)
			(layer "B.Fab")
		)
		(fp_line
			(start -0.508 -0.3048)
			(end 0.508 -0.3048)
			(stroke
				(width 0.1)
				(type default)
			)
			(layer "B.Fab")
		)
		(fp_line
			(start 0.508 -0.3048)
			(end 0.508 0.3048)
			(stroke
				(width 0.1)
				(type default)
			)
			(layer "B.Fab")
		)
		(pad "1" smd rect
			(at 0.5334 0 90)
			(size 0.7112 0.6096)
			(layers "B.Cu" "B.Mask" "B.Paste")
			(net "XP3R3V_FPGA")
		)
		(pad "2" smd rect
			(at -0.5334 0 90)
			(size 0.7112 0.6096)
			(layers "B.Cu" "B.Mask" "B.Paste")
			(net "SHT3X_I2C_SDA")
		)
		(zone
			(layer "B.Cu")
			(hatch none 0.5)
			(connect_pads
				(clearance 0)
			)
			(min_thickness 0.25)
			(keepout
				(tracks allowed)
				(vias not_allowed)
				(pads allowed)
				(copperpour not_allowed)
				(footprints allowed)
			)
			(placement
				(enabled no)
				(sheetname "")
			)
			(fill
				(thermal_gap 0.5)
				(thermal_bridge_width 0.5)
				(island_removal_mode 0)
			)
			(polygon
				(pts
					(xy 150.038308 -48.93691) (xy 150.647908 -48.93691) (xy 150.647908 -49.08931) (xy 150.038308 -49.08931)
				)
			)
		)
	)
)
